(kicad_pcb
	(version 20260206)
	(generator "pcbnew")
	(generator_version "10.0")
	(general
		(thickness 1.6)
		(legacy_teardrops no)
	)
	(paper "A4")
	(title_block
		(title "01162023_DA0F0TEBIF0_F0T_Expander_BD_F_brd_V02_OCP.brd")
		(comment 1 "Grand Teton / footprints 5781-5786 of 9728")
	)
	(layers
		(0 "F.Cu" signal "TOP")
		(4 "In1.Cu" signal "GND")
		(6 "In2.Cu" signal "VCC")
		(8 "In3.Cu" signal "VCC1")
		(10 "In4.Cu" signal "GND1")
		(12 "In5.Cu" signal "IN1")
		(14 "In6.Cu" signal "GND2")
		(16 "In7.Cu" signal "IN2")
		(18 "In8.Cu" signal "GND3")
		(20 "In9.Cu" signal "IN3")
		(22 "In10.Cu" signal "GND4")
		(24 "In11.Cu" signal "IN4")
		(26 "In12.Cu" signal "GND5")
		(28 "In13.Cu" signal "IN5")
		(30 "In14.Cu" signal "GND6")
		(32 "In15.Cu" signal "IN6")
		(34 "In16.Cu" signal "GND7")
		(2 "B.Cu" signal "BOTTOM")
		(9 "F.Adhes" user "F.Adhesive")
		(11 "B.Adhes" user "B.Adhesive")
		(13 "F.Paste" user "Package Geometry/Pastemask Top")
		(15 "B.Paste" user "Package Geometry/Pastemask Bottom")
		(5 "F.SilkS" user "Ref Des/Silkscreen Top")
		(7 "B.SilkS" user "Ref Des/Silkscreen Bottom")
		(1 "F.Mask" user "Board Geometry/Soldermask Top")
		(3 "B.Mask" user "Board Geometry/Soldermask Bottom")
		(17 "Dwgs.User" user "User.Drawings")
		(19 "Cmts.User" user "User.Comments")
		(21 "Eco1.User" user "User.Eco1")
		(23 "Eco2.User" user "User.Eco2")
		(25 "Edge.Cuts" user "Board Geometry/Outline")
		(27 "Margin" user)
		(31 "F.CrtYd" user "Package Geometry/Place Bound Top")
		(29 "B.CrtYd" user "Package Geometry/Place Bound Bottom")
		(35 "F.Fab" user "Ref Des/Assembly Top")
		(33 "B.Fab" user "Ref Des/Assembly Bottom")
	)
	(footprint ""
		(layer "F.Cu")
		(at 157.301438 -55.78475 -90)
		(property "Reference" "PD27"
			(at 1.881378 2.156968 90)
			(unlocked yes)
			(layer "F.SilkS")
			(effects
				(font
					(size 0.7874 0.5842)
					(thickness 0.1524)
				)
				(justify left)
			)
		)
		(property "Value" ""
			(at 0 0 270)
			(layer "F.Fab")
			(effects
				(font
					(size 1.27 1.27)
				)
			)
		)
		(duplicate_pad_numbers_are_jumpers no)
		(fp_line
			(start -3.400044 1.459992)
			(end -3.400044 -1.459992)
			(stroke
				(width 0.1524)
				(type default)
			)
			(layer "F.SilkS")
		)
		(fp_line
			(start 4.107942 1.459992)
			(end -3.400044 1.459992)
			(stroke
				(width 0.1524)
				(type default)
			)
			(layer "F.SilkS")
		)
		(fp_line
			(start -3.400044 -1.459992)
			(end 4.107942 -1.459992)
			(stroke
				(width 0.1524)
				(type default)
			)
			(layer "F.SilkS")
		)
		(fp_line
			(start 4.107942 -1.459992)
			(end 4.107942 1.459992)
			(stroke
				(width 0.1524)
				(type default)
			)
			(layer "F.SilkS")
		)
		(fp_poly
			(pts
				(xy 4.107942 -1.459992) (xy 4.107942 1.459992) (xy 3.308096 1.459992) (xy 3.308096 -1.459992)
			)
			(stroke
				(width 0)
				(type default)
			)
			(fill yes)
			(layer "F.SilkS")
		)
		(fp_line
			(start -2.29997 1.459992)
			(end -2.29997 -1.459992)
			(stroke
				(width 0.1)
				(type default)
			)
			(layer "F.Fab")
		)
		(fp_line
			(start 2.29997 1.459992)
			(end -2.29997 1.459992)
			(stroke
				(width 0.1)
				(type default)
			)
			(layer "F.Fab")
		)
		(fp_line
			(start -2.29997 -1.459992)
			(end 2.29997 -1.459992)
			(stroke
				(width 0.1)
				(type default)
			)
			(layer "F.Fab")
		)
		(fp_line
			(start 2.29997 -1.459992)
			(end 2.29997 1.459992)
			(stroke
				(width 0.1)
				(type default)
			)
			(layer "F.Fab")
		)
		(fp_text user "-"
			(at 5.4102 0.29845 90)
			(unlocked yes)
			(layer "F.SilkS")
			(effects
				(font
					(size 1.905 1.4224)
					(thickness 0.1524)
				)
				(justify left)
			)
		)
		(fp_text user "+"
			(at -4.7752 -0.12065 270)
			(unlocked yes)
			(layer "F.SilkS")
			(effects
				(font
					(size 1.905 1.4224)
					(thickness 0.1524)
				)
				(justify left)
			)
		)
		(fp_text user "-"
			(at 5.4102 0.29845 90)
			(unlocked yes)
			(layer "F.Fab")
			(effects
				(font
					(size 1.905 1.4224)
					(thickness 0.1524)
				)
				(justify left)
			)
		)
		(fp_text user "+"
			(at -4.7752 -0.12065 270)
			(unlocked yes)
			(layer "F.Fab")
			(effects
				(font
					(size 1.905 1.4224)
					(thickness 0.1524)
				)
				(justify left)
			)
		)
		(pad "A" smd rect
			(at -1.999996 0)
			(size 1.7018 2.5146)
			(layers "F.Cu" "F.Mask" "F.Paste")
			(net "GND")
		)
		(pad "C" smd rect
			(at 1.999996 0)
			(size 1.7018 2.5146)
			(layers "F.Cu" "F.Mask" "F.Paste")
			(net "P12V_SSD5_R")
		)
	)
	(footprint ""
		(layer "F.Cu")
		(at 400.567906 -53.051456)
		(property "Reference" "R4469"
			(at 0 0 0)
			(layer "F.SilkS")
			(hide yes)
			(effects
				(font
					(size 1.27 1.27)
				)
			)
		)
		(property "Value" ""
			(at 0 0 0)
			(layer "F.Fab")
			(effects
				(font
					(size 1.27 1.27)
				)
			)
		)
		(duplicate_pad_numbers_are_jumpers no)
		(fp_line
			(start -0.7874 -0.4064)
			(end 0.7874 -0.4064)
			(stroke
				(width 0.1524)
				(type default)
			)
			(layer "F.SilkS")
		)
		(fp_line
			(start -0.7874 0.4064)
			(end -0.7874 -0.4064)
			(stroke
				(width 0.1524)
				(type default)
			)
			(layer "F.SilkS")
		)
		(fp_line
			(start 0.7874 -0.4064)
			(end 0.7874 0.4064)
			(stroke
				(width 0.1524)
				(type default)
			)
			(layer "F.SilkS")
		)
		(fp_line
			(start 0.7874 0.4064)
			(end -0.7874 0.4064)
			(stroke
				(width 0.1524)
				(type default)
			)
			(layer "F.SilkS")
		)
		(fp_line
			(start -0.67945 -0.305054)
			(end -0.12065 -0.305054)
			(stroke
				(width 0.1)
				(type default)
			)
			(layer "F.Fab")
		)
		(fp_line
			(start -0.67945 0.3048)
			(end -0.67945 -0.305054)
			(stroke
				(width 0.1)
				(type default)
			)
			(layer "F.Fab")
		)
		(fp_line
			(start -0.12065 -0.305054)
			(end -0.12065 -0.2794)
			(stroke
				(width 0.1)
				(type default)
			)
			(layer "F.Fab")
		)
		(fp_line
			(start -0.12065 -0.2794)
			(end 0.12065 -0.2794)
			(stroke
				(width 0.1)
				(type default)
			)
			(layer "F.Fab")
		)
		(fp_line
			(start -0.12065 0.2794)
			(end -0.12065 0.3048)
			(stroke
				(width 0.1)
				(type default)
			)
			(layer "F.Fab")
		)
		(fp_line
			(start -0.12065 0.3048)
			(end -0.67945 0.3048)
			(stroke
				(width 0.1)
				(type default)
			)
			(layer "F.Fab")
		)
		(fp_line
			(start 0.120396 0.2794)
			(end -0.12065 0.2794)
			(stroke
				(width 0.1)
				(type default)
			)
			(layer "F.Fab")
		)
		(fp_line
			(start 0.120396 0.3048)
			(end 0.120396 0.2794)
			(stroke
				(width 0.1)
				(type default)
			)
			(layer "F.Fab")
		)
		(fp_line
			(start 0.12065 -0.3048)
			(end 0.67945 -0.3048)
			(stroke
				(width 0.1)
				(type default)
			)
			(layer "F.Fab")
		)
		(fp_line
			(start 0.12065 -0.2794)
			(end 0.12065 -0.3048)
			(stroke
				(width 0.1)
				(type default)
			)
			(layer "F.Fab")
		)
		(fp_line
			(start 0.67945 -0.3048)
			(end 0.67945 0.3048)
			(stroke
				(width 0.1)
				(type default)
			)
			(layer "F.Fab")
		)
		(fp_line
			(start 0.67945 0.3048)
			(end 0.120396 0.3048)
			(stroke
				(width 0.1)
				(type default)
			)
			(layer "F.Fab")
		)
		(pad "1" smd circle
			(at -0.40005 0)
			(size 0 0)
			(layers "F.Cu" "F.Mask" "F.Paste")
			(net "PWRGD_P12V_SSD13")
		)
		(pad "2" smd circle
			(at 0.40005 0)
			(size 0 0)
			(layers "F.Cu" "F.Mask" "F.Paste")
			(net "PWRGD_P12V_SSD13_R")
		)
	)
	(footprint ""
		(layer "F.Cu")
		(at 7.613396 -134.042404)
		(property "Reference" "R4444"
			(at 0 0 0)
			(layer "F.SilkS")
			(hide yes)
			(effects
				(font
					(size 1.27 1.27)
				)
			)
		)
		(property "Value" ""
			(at 0 0 0)
			(layer "F.Fab")
			(effects
				(font
					(size 1.27 1.27)
				)
			)
		)
		(duplicate_pad_numbers_are_jumpers no)
		(fp_line
			(start -0.7874 -0.4064)
			(end 0.7874 -0.4064)
			(stroke
				(width 0.1524)
				(type default)
			)
			(layer "F.SilkS")
		)
		(fp_line
			(start -0.7874 0.4064)
			(end -0.7874 -0.4064)
			(stroke
				(width 0.1524)
				(type default)
			)
			(layer "F.SilkS")
		)
		(fp_line
			(start 0.7874 -0.4064)
			(end 0.7874 0.4064)
			(stroke
				(width 0.1524)
				(type default)
			)
			(layer "F.SilkS")
		)
		(fp_line
			(start 0.7874 0.4064)
			(end -0.7874 0.4064)
			(stroke
				(width 0.1524)
				(type default)
			)
			(layer "F.SilkS")
		)
		(fp_line
			(start -0.67945 -0.305054)
			(end -0.12065 -0.305054)
			(stroke
				(width 0.1)
				(type default)
			)
			(layer "F.Fab")
		)
		(fp_line
			(start -0.67945 0.3048)
			(end -0.67945 -0.305054)
			(stroke
				(width 0.1)
				(type default)
			)
			(layer "F.Fab")
		)
		(fp_line
			(start -0.12065 -0.305054)
			(end -0.12065 -0.2794)
			(stroke
				(width 0.1)
				(type default)
			)
			(layer "F.Fab")
		)
		(fp_line
			(start -0.12065 -0.2794)
			(end 0.12065 -0.2794)
			(stroke
				(width 0.1)
				(type default)
			)
			(layer "F.Fab")
		)
		(fp_line
			(start -0.12065 0.2794)
			(end -0.12065 0.3048)
			(stroke
				(width 0.1)
				(type default)
			)
			(layer "F.Fab")
		)
		(fp_line
			(start -0.12065 0.3048)
			(end -0.67945 0.3048)
			(stroke
				(width 0.1)
				(type default)
			)
			(layer "F.Fab")
		)
		(fp_line
			(start 0.120396 0.2794)
			(end -0.12065 0.2794)
			(stroke
				(width 0.1)
				(type default)
			)
			(layer "F.Fab")
		)
		(fp_line
			(start 0.120396 0.3048)
			(end 0.120396 0.2794)
			(stroke
				(width 0.1)
				(type default)
			)
			(layer "F.Fab")
		)
		(fp_line
			(start 0.12065 -0.3048)
			(end 0.67945 -0.3048)
			(stroke
				(width 0.1)
				(type default)
			)
			(layer "F.Fab")
		)
		(fp_line
			(start 0.12065 -0.2794)
			(end 0.12065 -0.3048)
			(stroke
				(width 0.1)
				(type default)
			)
			(layer "F.Fab")
		)
		(fp_line
			(start 0.67945 -0.3048)
			(end 0.67945 0.3048)
			(stroke
				(width 0.1)
				(type default)
			)
			(layer "F.Fab")
		)
		(fp_line
			(start 0.67945 0.3048)
			(end 0.120396 0.3048)
			(stroke
				(width 0.1)
				(type default)
			)
			(layer "F.Fab")
		)
		(pad "1" smd circle
			(at -0.40005 0)
			(size 0 0)
			(layers "F.Cu" "F.Mask" "F.Paste")
			(net "HP_NIC0_EN")
		)
		(pad "2" smd circle
			(at 0.40005 0)
			(size 0 0)
			(layers "F.Cu" "F.Mask" "F.Paste")
			(net "P12V_NIC0_EN_R")
		)
	)
	(footprint ""
		(layer "F.Cu")
		(at 107.70616 -137.43686 -90)
		(property "Reference" "PC37"
			(at 0 0 270)
			(layer "F.SilkS")
			(hide yes)
			(effects
				(font
					(size 1.27 1.27)
				)
			)
		)
		(property "Value" ""
			(at 0 0 270)
			(layer "F.Fab")
			(effects
				(font
					(size 1.27 1.27)
				)
			)
		)
		(duplicate_pad_numbers_are_jumpers no)
		(fp_line
			(start -1.988058 2.750058)
			(end 2.750058 2.750058)
			(stroke
				(width 0.1524)
				(type default)
			)
			(layer "F.SilkS")
		)
		(fp_line
			(start 2.750058 2.750058)
			(end 2.750058 0.9398)
			(stroke
				(width 0.1524)
				(type default)
			)
			(layer "F.SilkS")
		)
		(fp_line
			(start -2.750058 1.988058)
			(end -1.988058 2.750058)
			(stroke
				(width 0.1524)
				(type default)
			)
			(layer "F.SilkS")
		)
		(fp_line
			(start -2.750058 0.9398)
			(end -2.750058 1.988058)
			(stroke
				(width 0.1524)
				(type default)
			)
			(layer "F.SilkS")
		)
		(fp_line
			(start 2.750058 -0.9398)
			(end 2.750058 -2.750058)
			(stroke
				(width 0.1524)
				(type default)
			)
			(layer "F.SilkS")
		)
		(fp_line
			(start -2.750058 -1.988058)
			(end -2.750058 -0.9398)
			(stroke
				(width 0.1524)
				(type default)
			)
			(layer "F.SilkS")
		)
		(fp_line
			(start -1.988058 -2.750058)
			(end -2.750058 -1.988058)
			(stroke
				(width 0.1524)
				(type default)
			)
			(layer "F.SilkS")
		)
		(fp_line
			(start 2.750058 -2.750058)
			(end -1.988058 -2.750058)
			(stroke
				(width 0.1524)
				(type default)
			)
			(layer "F.SilkS")
		)
		(fp_line
			(start -2.750058 2.750058)
			(end 2.750058 2.750058)
			(stroke
				(width 0.1)
				(type default)
			)
			(layer "F.Fab")
		)
		(fp_line
			(start 2.750058 2.750058)
			(end 2.750058 -2.750058)
			(stroke
				(width 0.1)
				(type default)
			)
			(layer "F.Fab")
		)
		(fp_line
			(start -2.750058 -2.750058)
			(end -2.750058 2.750058)
			(stroke
				(width 0.1)
				(type default)
			)
			(layer "F.Fab")
		)
		(fp_line
			(start 2.750058 -2.750058)
			(end -2.750058 -2.750058)
			(stroke
				(width 0.1)
				(type default)
			)
			(layer "F.Fab")
		)
		(pad "1" smd rect
			(at -2.199894 0)
			(size 1.6002 3.0226)
			(layers "F.Cu" "F.Mask" "F.Paste")
			(net "P3V3_AUX")
		)
		(pad "2" smd rect
			(at 2.199894 0)
			(size 1.6002 3.0226)
			(layers "F.Cu" "F.Mask" "F.Paste")
			(net "GND")
		)
	)
	(footprint ""
		(layer "F.Cu")
		(at 147.966938 -52.543456 180)
		(property "Reference" "PC514"
			(at 0 0 180)
			(layer "F.SilkS")
			(hide yes)
			(effects
				(font
					(size 1.27 1.27)
				)
			)
		)
		(property "Value" ""
			(at 0 0 180)
			(layer "F.Fab")
			(effects
				(font
					(size 1.27 1.27)
				)
			)
		)
		(duplicate_pad_numbers_are_jumpers no)
		(fp_line
			(start 0.7874 0.4064)
			(end -0.7874 0.4064)
			(stroke
				(width 0.1524)
				(type default)
			)
			(layer "F.SilkS")
		)
		(fp_line
			(start 0.7874 -0.4064)
			(end 0.7874 0.4064)
			(stroke
				(width 0.1524)
				(type default)
			)
			(layer "F.SilkS")
		)
		(fp_line
			(start -0.7874 0.4064)
			(end -0.7874 -0.4064)
			(stroke
				(width 0.1524)
				(type default)
			)
			(layer "F.SilkS")
		)
		(fp_line
			(start -0.7874 -0.4064)
			(end 0.7874 -0.4064)
			(stroke
				(width 0.1524)
				(type default)
			)
			(layer "F.SilkS")
		)
		(fp_line
			(start 0.67945 0.3048)
			(end 0.120396 0.3048)
			(stroke
				(width 0.1)
				(type default)
			)
			(layer "F.Fab")
		)
		(fp_line
			(start 0.67945 -0.3048)
			(end 0.67945 0.3048)
			(stroke
				(width 0.1)
				(type default)
			)
			(layer "F.Fab")
		)
		(fp_line
			(start 0.12065 -0.2794)
			(end 0.12065 -0.3048)
			(stroke
				(width 0.1)
				(type default)
			)
			(layer "F.Fab")
		)
		(fp_line
			(start 0.12065 -0.3048)
			(end 0.67945 -0.3048)
			(stroke
				(width 0.1)
				(type default)
			)
			(layer "F.Fab")
		)
		(fp_line
			(start 0.120396 0.3048)
			(end 0.120396 0.2794)
			(stroke
				(width 0.1)
				(type default)
			)
			(layer "F.Fab")
		)
		(fp_line
			(start 0.120396 0.2794)
			(end -0.12065 0.2794)
			(stroke
				(width 0.1)
				(type default)
			)
			(layer "F.Fab")
		)
		(fp_line
			(start -0.12065 0.3048)
			(end -0.67945 0.3048)
			(stroke
				(width 0.1)
				(type default)
			)
			(layer "F.Fab")
		)
		(fp_line
			(start -0.12065 0.2794)
			(end -0.12065 0.3048)
			(stroke
				(width 0.1)
				(type default)
			)
			(layer "F.Fab")
		)
		(fp_line
			(start -0.12065 -0.2794)
			(end 0.12065 -0.2794)
			(stroke
				(width 0.1)
				(type default)
			)
			(layer "F.Fab")
		)
		(fp_line
			(start -0.12065 -0.305054)
			(end -0.12065 -0.2794)
			(stroke
				(width 0.1)
				(type default)
			)
			(layer "F.Fab")
		)
		(fp_line
			(start -0.67945 0.3048)
			(end -0.67945 -0.305054)
			(stroke
				(width 0.1)
				(type default)
			)
			(layer "F.Fab")
		)
		(fp_line
			(start -0.67945 -0.305054)
			(end -0.12065 -0.305054)
			(stroke
				(width 0.1)
				(type default)
			)
			(layer "F.Fab")
		)
		(pad "1" smd circle
			(at -0.40005 0 180)
			(size 0 0)
			(layers "F.Cu" "F.Mask" "F.Paste")
			(net "P3V3_SSD5")
		)
		(pad "2" smd circle
			(at 0.40005 0 180)
			(size 0 0)
			(layers "F.Cu" "F.Mask" "F.Paste")
			(net "GND")
		)
	)
	(footprint ""
		(layer "F.Cu")
		(at 260.038596 -311.156604 -90)
		(property "Reference" "R1330"
			(at 0 0 270)
			(layer "F.SilkS")
			(hide yes)
			(effects
				(font
					(size 1.27 1.27)
				)
			)
		)
		(property "Value" ""
			(at 0 0 270)
			(layer "F.Fab")
			(effects
				(font
					(size 1.27 1.27)
				)
			)
		)
		(duplicate_pad_numbers_are_jumpers no)
		(fp_line
			(start -0.7874 0.4064)
			(end -0.7874 -0.4064)
			(stroke
				(width 0.1524)
				(type default)
			)
			(layer "F.SilkS")
		)
		(fp_line
			(start 0.7874 0.4064)
			(end -0.7874 0.4064)
			(stroke
				(width 0.1524)
				(type default)
			)
			(layer "F.SilkS")
		)
		(fp_line
			(start -0.7874 -0.4064)
			(end 0.7874 -0.4064)
			(stroke
				(width 0.1524)
				(type default)
			)
			(layer "F.SilkS")
		)
		(fp_line
			(start 0.7874 -0.4064)
			(end 0.7874 0.4064)
			(stroke
				(width 0.1524)
				(type default)
			)
			(layer "F.SilkS")
		)
		(fp_line
			(start -0.67945 0.3048)
			(end -0.67945 -0.305054)
			(stroke
				(width 0.1)
				(type default)
			)
			(layer "F.Fab")
		)
		(fp_line
			(start -0.12065 0.3048)
			(end -0.67945 0.3048)
			(stroke
				(width 0.1)
				(type default)
			)
			(layer "F.Fab")
		)
		(fp_line
			(start 0.120396 0.3048)
			(end 0.120396 0.2794)
			(stroke
				(width 0.1)
				(type default)
			)
			(layer "F.Fab")
		)
		(fp_line
			(start 0.67945 0.3048)
			(end 0.120396 0.3048)
			(stroke
				(width 0.1)
				(type default)
			)
			(layer "F.Fab")
		)
		(fp_line
			(start -0.12065 0.2794)
			(end -0.12065 0.3048)
			(stroke
				(width 0.1)
				(type default)
			)
			(layer "F.Fab")
		)
		(fp_line
			(start 0.120396 0.2794)
			(end -0.12065 0.2794)
			(stroke
				(width 0.1)
				(type default)
			)
			(layer "F.Fab")
		)
		(fp_line
			(start -0.12065 -0.2794)
			(end 0.12065 -0.2794)
			(stroke
				(width 0.1)
				(type default)
			)
			(layer "F.Fab")
		)
		(fp_line
			(start 0.12065 -0.2794)
			(end 0.12065 -0.3048)
			(stroke
				(width 0.1)
				(type default)
			)
			(layer "F.Fab")
		)
		(fp_line
			(start 0.12065 -0.3048)
			(end 0.67945 -0.3048)
			(stroke
				(width 0.1)
				(type default)
			)
			(layer "F.Fab")
		)
		(fp_line
			(start 0.67945 -0.3048)
			(end 0.67945 0.3048)
			(stroke
				(width 0.1)
				(type default)
			)
			(layer "F.Fab")
		)
		(fp_line
			(start -0.67945 -0.305054)
			(end -0.12065 -0.305054)
			(stroke
				(width 0.1)
				(type default)
			)
			(layer "F.Fab")
		)
		(fp_line
			(start -0.12065 -0.305054)
			(end -0.12065 -0.2794)
			(stroke
				(width 0.1)
				(type default)
			)
			(layer "F.Fab")
		)
		(pad "1" smd circle
			(at -0.40005 0 270)
			(size 0 0)
			(layers "F.Cu" "F.Mask" "F.Paste")
			(net "PEX2_DBG_SEL1")
		)
		(pad "2" smd circle
			(at 0.40005 0 270)
			(size 0 0)
			(layers "F.Cu" "F.Mask" "F.Paste")
			(net "P1V8_PEX")
		)
	)
)
